(kicad_pcb
	(version 20260206)
	(generator "pcbnew")
	(generator_version "10.0")
	(general
		(thickness 1.6)
		(legacy_teardrops no)
	)
	(paper "A4")
	(title_block
		(title "Bryce Canyon_IOM_IOC_16318-2_OCP.brd")
		(comment 1 "Bryce Canyon / footprints 492-497 of 1605")
	)
	(layers
		(0 "F.Cu" signal "TOP")
		(4 "In1.Cu" signal "L2GND")
		(6 "In2.Cu" signal "L3")
		(8 "In3.Cu" signal "L4VCC")
		(10 "In4.Cu" signal "L5VCC")
		(12 "In5.Cu" signal "L6")
		(14 "In6.Cu" signal "L7GND")
		(2 "B.Cu" signal "BOTTOM")
		(9 "F.Adhes" user "F.Adhesive")
		(11 "B.Adhes" user "B.Adhesive")
		(13 "F.Paste" user "Package Geometry/Pastemask Top")
		(15 "B.Paste" user "Package Geometry/Pastemask Bottom")
		(5 "F.SilkS" user "Ref Des/Silkscreen Top")
		(7 "B.SilkS" user "Ref Des/Silkscreen Bottom")
		(1 "F.Mask" user "Board Geometry/Soldermask Top")
		(3 "B.Mask" user "Board Geometry/Soldermask Bottom")
		(17 "Dwgs.User" user "User.Drawings")
		(19 "Cmts.User" user "User.Comments")
		(21 "Eco1.User" user "User.Eco1")
		(23 "Eco2.User" user "User.Eco2")
		(25 "Edge.Cuts" user "Board Geometry/Outline")
		(27 "Margin" user)
		(31 "F.CrtYd" user "Package Geometry/Place Bound Top")
		(29 "B.CrtYd" user "Package Geometry/Place Bound Bottom")
		(35 "F.Fab" user "Ref Des/Assembly Top")
		(33 "B.Fab" user "Ref Des/Assembly Bottom")
	)
	(footprint ""
		(layer "F.Cu")
		(at 213.6902 -15.13332 180)
		(property "Reference" "R746"
			(at 0 0 180)
			(layer "F.SilkS")
			(hide yes)
			(effects
				(font
					(size 1.27 1.27)
				)
			)
		)
		(property "Value" "1KR2F-3-GP"
			(at 0.064008 -3.993896 180)
			(unlocked yes)
			(layer "F.Fab")
			(hide yes)
			(effects
				(font
					(size 1.016 1.016)
					(thickness 0.1524)
				)
			)
		)
		(property "Device Type" "R402H16"
			(at 0.064008 -5.517896 180)
			(unlocked yes)
			(layer "F.Fab")
			(hide yes)
			(effects
				(font
					(size 1.016 1.016)
					(thickness 0.1524)
				)
			)
		)
		(duplicate_pad_numbers_are_jumpers no)
		(fp_line
			(start 0.508 -0.9398)
			(end -0.508 -0.9398)
			(stroke
				(width 0.1524)
				(type default)
			)
			(layer "F.SilkS")
		)
		(fp_line
			(start -0.508 -0.9398)
			(end -0.508 0.9398)
			(stroke
				(width 0.1524)
				(type default)
			)
			(layer "F.SilkS")
		)
		(fp_rect
			(start -0.508 0.9398)
			(end 0.508 -0.9398)
			(stroke
				(width 0)
				(type default)
			)
			(fill no)
			(layer "F.CrtYd")
		)
		(fp_rect
			(start -0.508 0.9398)
			(end 0.508 -0.9398)
			(stroke
				(width 0)
				(type default)
			)
			(fill no)
			(layer "F.Fab")
		)
		(pad "1" smd custom
			(at 0 -0.4445 180)
			(size 0.1397 0.1397)
			(layers "F.Cu" "F.Mask" "F.Paste")
			(net "P5V_STBY")
			(options
				(clearance outline)
				(anchor circle)
			)
			(primitives
				(gr_poly
					(pts
						(arc
							(start -0.1778 -0.2794)
							(mid -0.249642 -0.249642)
							(end -0.2794 -0.1778)
						)
						(arc
							(start -0.2794 0.1778)
							(mid -0.249642 0.249642)
							(end -0.1778 0.2794)
						)
						(arc
							(start 0.1778 0.2794)
							(mid 0.249642 0.249642)
							(end 0.2794 0.1778)
						)
						(arc
							(start 0.2794 -0.1778)
							(mid 0.249642 -0.249642)
							(end 0.1778 -0.2794)
						)
					)
					(width 0)
					(fill yes)
				)
			)
		)
		(pad "2" smd custom
			(at 0 0.4445 180)
			(size 0.1397 0.1397)
			(layers "F.Cu" "F.Mask" "F.Paste")
			(net "BMC_ML_PWR_BLUE_LED_L")
			(options
				(clearance outline)
				(anchor circle)
			)
			(primitives
				(gr_poly
					(pts
						(arc
							(start -0.1778 -0.2794)
							(mid -0.249642 -0.249642)
							(end -0.2794 -0.1778)
						)
						(arc
							(start -0.2794 0.1778)
							(mid -0.249642 0.249642)
							(end -0.1778 0.2794)
						)
						(arc
							(start 0.1778 0.2794)
							(mid 0.249642 0.249642)
							(end 0.2794 0.1778)
						)
						(arc
							(start 0.2794 -0.1778)
							(mid 0.249642 -0.249642)
							(end 0.1778 -0.2794)
						)
					)
					(width 0)
					(fill yes)
				)
			)
		)
	)
	(footprint ""
		(layer "F.Cu")
		(at 142.0368 -10.7442)
		(property "Reference" "C517"
			(at 0 0 0)
			(layer "F.SilkS")
			(hide yes)
			(effects
				(font
					(size 1.27 1.27)
				)
			)
		)
		(property "Value" "SCD1U16V2KX-3GP"
			(at 1.1811 -2.7051 0)
			(unlocked yes)
			(layer "F.Fab")
			(hide yes)
			(effects
				(font
					(size 1.016 1.016)
					(thickness 0.1524)
				)
			)
		)
		(property "Device Type" "C402H22"
			(at 1.1811 -4.2291 0)
			(unlocked yes)
			(layer "F.Fab")
			(hide yes)
			(effects
				(font
					(size 1.016 1.016)
					(thickness 0.1524)
				)
			)
		)
		(duplicate_pad_numbers_are_jumpers no)
		(fp_rect
			(start -0.4318 0.9525)
			(end 0.4318 -0.9525)
			(stroke
				(width 0)
				(type default)
			)
			(fill no)
			(layer "F.CrtYd")
		)
		(fp_rect
			(start -0.4318 0.9525)
			(end 0.4318 -0.9525)
			(stroke
				(width 0)
				(type default)
			)
			(fill no)
			(layer "F.Fab")
		)
		(pad "1" smd custom
			(at 0 -0.4445)
			(size 0.1524 0.1524)
			(layers "F.Cu" "F.Mask" "F.Paste")
			(net "P1V8")
			(options
				(clearance outline)
				(anchor circle)
			)
			(primitives
				(gr_poly
					(pts
						(arc
							(start 0.3048 -0.2032)
							(mid 0.275042 -0.275042)
							(end 0.2032 -0.3048)
						)
						(arc
							(start -0.2032 -0.3048)
							(mid -0.275042 -0.275042)
							(end -0.3048 -0.2032)
						)
						(arc
							(start -0.3048 0.2032)
							(mid -0.275042 0.275042)
							(end -0.2032 0.3048)
						)
						(arc
							(start 0.2032 0.3048)
							(mid 0.275042 0.275042)
							(end 0.3048 0.2032)
						)
					)
					(width 0)
					(fill yes)
				)
			)
		)
		(pad "2" smd custom
			(at 0 0.4445)
			(size 0.1524 0.1524)
			(layers "F.Cu" "F.Mask" "F.Paste")
			(net "GND")
			(options
				(clearance outline)
				(anchor circle)
			)
			(primitives
				(gr_poly
					(pts
						(arc
							(start 0.3048 -0.2032)
							(mid 0.275042 -0.275042)
							(end 0.2032 -0.3048)
						)
						(arc
							(start -0.2032 -0.3048)
							(mid -0.275042 -0.275042)
							(end -0.3048 -0.2032)
						)
						(arc
							(start -0.3048 0.2032)
							(mid -0.275042 0.275042)
							(end -0.2032 0.3048)
						)
						(arc
							(start 0.2032 0.3048)
							(mid 0.275042 0.275042)
							(end 0.3048 0.2032)
						)
					)
					(width 0)
					(fill yes)
				)
			)
		)
	)
	(footprint ""
		(layer "F.Cu")
		(at 171.753276 -149.333966)
		(property "Reference" "C159"
			(at 0 0 0)
			(layer "F.SilkS")
			(hide yes)
			(effects
				(font
					(size 1.27 1.27)
				)
			)
		)
		(property "Value" "SC2200P50V2KX-2GP"
			(at 1.1811 -2.7051 0)
			(unlocked yes)
			(layer "F.Fab")
			(hide yes)
			(effects
				(font
					(size 1.016 1.016)
					(thickness 0.1524)
				)
			)
		)
		(property "Device Type" "C402H22"
			(at 1.1811 -4.2291 0)
			(unlocked yes)
			(layer "F.Fab")
			(hide yes)
			(effects
				(font
					(size 1.016 1.016)
					(thickness 0.1524)
				)
			)
		)
		(duplicate_pad_numbers_are_jumpers no)
		(fp_rect
			(start -0.4318 0.9525)
			(end 0.4318 -0.9525)
			(stroke
				(width 0)
				(type default)
			)
			(fill no)
			(layer "F.CrtYd")
		)
		(fp_rect
			(start -0.4318 0.9525)
			(end 0.4318 -0.9525)
			(stroke
				(width 0)
				(type default)
			)
			(fill no)
			(layer "F.Fab")
		)
		(pad "1" smd custom
			(at 0 -0.4445)
			(size 0.1524 0.1524)
			(layers "F.Cu" "F.Mask" "F.Paste")
			(net "P5V_LL")
			(options
				(clearance outline)
				(anchor circle)
			)
			(primitives
				(gr_poly
					(pts
						(arc
							(start 0.3048 -0.2032)
							(mid 0.275042 -0.275042)
							(end 0.2032 -0.3048)
						)
						(arc
							(start -0.2032 -0.3048)
							(mid -0.275042 -0.275042)
							(end -0.3048 -0.2032)
						)
						(arc
							(start -0.3048 0.2032)
							(mid -0.275042 0.275042)
							(end -0.2032 0.3048)
						)
						(arc
							(start 0.2032 0.3048)
							(mid 0.275042 0.275042)
							(end 0.3048 0.2032)
						)
					)
					(width 0)
					(fill yes)
				)
			)
		)
		(pad "2" smd custom
			(at 0 0.4445)
			(size 0.1524 0.1524)
			(layers "F.Cu" "F.Mask" "F.Paste")
			(net "P5V_SNB")
			(options
				(clearance outline)
				(anchor circle)
			)
			(primitives
				(gr_poly
					(pts
						(arc
							(start 0.3048 -0.2032)
							(mid 0.275042 -0.275042)
							(end 0.2032 -0.3048)
						)
						(arc
							(start -0.2032 -0.3048)
							(mid -0.275042 -0.275042)
							(end -0.3048 -0.2032)
						)
						(arc
							(start -0.3048 0.2032)
							(mid -0.275042 0.275042)
							(end -0.2032 0.3048)
						)
						(arc
							(start 0.2032 0.3048)
							(mid 0.275042 0.275042)
							(end 0.3048 0.2032)
						)
					)
					(width 0)
					(fill yes)
				)
			)
		)
	)
	(footprint ""
		(layer "F.Cu")
		(at 36.76904 -121.360946 90)
		(property "Reference" "U11"
			(at 0 0 90)
			(layer "F.SilkS")
			(hide yes)
			(effects
				(font
					(size 1.27 1.27)
				)
			)
		)
		(property "Value" "W25Q256FVFIQ-GP"
			(at -6.7945 -2.2098 90)
			(unlocked yes)
			(layer "F.Fab")
			(hide yes)
			(effects
				(font
					(size 1.016 1.016)
					(thickness 0.1524)
				)
			)
		)
		(property "Device Type" "SOIC16-6H104"
			(at -6.7945 -3.7338 90)
			(unlocked yes)
			(layer "F.Fab")
			(hide yes)
			(effects
				(font
					(size 1.016 1.016)
					(thickness 0.1524)
				)
			)
		)
		(duplicate_pad_numbers_are_jumpers no)
		(fp_line
			(start 4.7498 -3.2258)
			(end 4.7498 3.2258)
			(stroke
				(width 0.1524)
				(type default)
			)
			(layer "F.SilkS")
		)
		(fp_line
			(start -5.588 -3.2258)
			(end 4.7498 -3.2258)
			(stroke
				(width 0.1524)
				(type default)
			)
			(layer "F.SilkS")
		)
		(fp_line
			(start -5.588 -0.50038)
			(end -5.08762 0)
			(stroke
				(width 0.1524)
				(type default)
			)
			(layer "F.SilkS")
		)
		(fp_line
			(start -5.08762 0)
			(end -5.588 0.50038)
			(stroke
				(width 0.1524)
				(type default)
			)
			(layer "F.SilkS")
		)
		(fp_line
			(start 4.7498 3.2258)
			(end -5.588 3.2258)
			(stroke
				(width 0.1524)
				(type default)
			)
			(layer "F.SilkS")
		)
		(fp_line
			(start -5.4102 3.2258)
			(end -5.4102 5.7912)
			(stroke
				(width 0.508)
				(type default)
			)
			(layer "F.SilkS")
		)
		(fp_line
			(start -5.588 3.2258)
			(end -5.588 -3.2258)
			(stroke
				(width 0.1524)
				(type default)
			)
			(layer "F.SilkS")
		)
		(fp_poly
			(pts
				(xy -4.764786 -3.2258) (xy 4.7625 -3.2258) (xy 4.7625 3.2258) (xy -4.764786 3.2258)
			)
			(stroke
				(width 0)
				(type default)
			)
			(fill yes)
			(layer "F.SilkS")
		)
		(fp_rect
			(start -5.1435 5.1562)
			(end 5.1435 -5.1562)
			(stroke
				(width 0)
				(type default)
			)
			(fill no)
			(layer "F.CrtYd")
		)
		(fp_poly
			(pts
				(xy -5.6642 6.0452) (xy -5.6642 -6.0452) (xy 5.6642 -6.0452) (xy 5.6642 -1.7653) (xy 5.1435 -1.7653)
				(xy 5.1435 -5.1562) (xy -5.1435 -5.1562) (xy -5.1435 5.1562) (xy 5.1435 5.1562) (xy 5.1435 -1.7526)
				(xy 5.6642 -1.7526) (xy 5.6642 6.0452)
			)
			(stroke
				(width 0)
				(type default)
			)
			(fill no)
			(layer "F.CrtYd")
		)
		(fp_rect
			(start -5.6642 6.0452)
			(end 5.6642 -6.0452)
			(stroke
				(width 0)
				(type default)
			)
			(fill no)
			(layer "F.Fab")
		)
		(pad "1" smd rect
			(at -4.445 4.71805 90)
			(size 0.635 1.651)
			(layers "F.Cu" "F.Mask" "F.Paste")
			(net "FLA0_SPI_HOLD_N")
		)
		(pad "2" smd rect
			(at -3.175 4.71805 90)
			(size 0.635 1.651)
			(layers "F.Cu" "F.Mask" "F.Paste")
			(net "P3V3_STBY")
		)
		(pad "3" smd rect
			(at -1.905 4.71805 90)
			(size 0.635 1.651)
			(layers "F.Cu" "F.Mask" "F.Paste")
			(net "FLA0_SPI_RST")
		)
		(pad "4" smd rect
			(at -0.635 4.71805 90)
			(size 0.635 1.651)
			(layers "F.Cu" "F.Mask" "F.Paste")
			(net "Net_340")
		)
		(pad "5" smd rect
			(at 0.635 4.71805 90)
			(size 0.635 1.651)
			(layers "F.Cu" "F.Mask" "F.Paste")
			(net "Net_341")
		)
		(pad "6" smd rect
			(at 1.905 4.71805 90)
			(size 0.635 1.651)
			(layers "F.Cu" "F.Mask" "F.Paste")
			(net "Net_342")
		)
		(pad "7" smd rect
			(at 3.175 4.71805 90)
			(size 0.635 1.651)
			(layers "F.Cu" "F.Mask" "F.Paste")
			(net "FLA_CS_0_R")
		)
		(pad "8" smd rect
			(at 4.445 4.71805 90)
			(size 0.635 1.651)
			(layers "F.Cu" "F.Mask" "F.Paste")
			(net "BMC_SPI_MISO_TPM")
		)
		(pad "9" smd rect
			(at 4.445 -4.71805 90)
			(size 0.635 1.651)
			(layers "F.Cu" "F.Mask" "F.Paste")
			(net "FLA0_WP_N")
		)
		(pad "10" smd rect
			(at 3.175 -4.71805 90)
			(size 0.635 1.651)
			(layers "F.Cu" "F.Mask" "F.Paste")
			(net "GND")
		)
		(pad "11" smd rect
			(at 1.905 -4.71805 90)
			(size 0.635 1.651)
			(layers "F.Cu" "F.Mask" "F.Paste")
			(net "Net_336")
		)
		(pad "12" smd rect
			(at 0.635 -4.71805 90)
			(size 0.635 1.651)
			(layers "F.Cu" "F.Mask" "F.Paste")
			(net "Net_337")
		)
		(pad "13" smd rect
			(at -0.635 -4.71805 90)
			(size 0.635 1.651)
			(layers "F.Cu" "F.Mask" "F.Paste")
			(net "Net_338")
		)
		(pad "14" smd rect
			(at -1.905 -4.71805 90)
			(size 0.635 1.651)
			(layers "F.Cu" "F.Mask" "F.Paste")
			(net "Net_339")
		)
		(pad "15" smd rect
			(at -3.175 -4.71805 90)
			(size 0.635 1.651)
			(layers "F.Cu" "F.Mask" "F.Paste")
			(net "BMC_SPI_MOSI_R")
		)
		(pad "16" smd rect
			(at -4.445 -4.71805 90)
			(size 0.635 1.651)
			(layers "F.Cu" "F.Mask" "F.Paste")
			(net "BMC_SPI_CLK_R")
		)
	)
	(footprint ""
		(layer "F.Cu")
		(at 46.02988 -120.395492 90)
		(property "Reference" "R765"
			(at 0 0 90)
			(layer "F.SilkS")
			(hide yes)
			(effects
				(font
					(size 1.27 1.27)
				)
			)
		)
		(property "Value" "0R2J-2-GP"
			(at 0.064008 -3.993896 90)
			(unlocked yes)
			(layer "F.Fab")
			(hide yes)
			(effects
				(font
					(size 1.016 1.016)
					(thickness 0.1524)
				)
			)
		)
		(property "Device Type" "R402H16"
			(at 0.064008 -5.517896 90)
			(unlocked yes)
			(layer "F.Fab")
			(hide yes)
			(effects
				(font
					(size 1.016 1.016)
					(thickness 0.1524)
				)
			)
		)
		(duplicate_pad_numbers_are_jumpers no)
		(fp_line
			(start 0.508 -0.9398)
			(end -0.508 -0.9398)
			(stroke
				(width 0.1524)
				(type default)
			)
			(layer "F.SilkS")
		)
		(fp_line
			(start -0.508 -0.9398)
			(end -0.508 0.9398)
			(stroke
				(width 0.1524)
				(type default)
			)
			(layer "F.SilkS")
		)
		(fp_rect
			(start -0.508 0.9398)
			(end 0.508 -0.9398)
			(stroke
				(width 0)
				(type default)
			)
			(fill no)
			(layer "F.CrtYd")
		)
		(fp_rect
			(start -0.508 0.9398)
			(end 0.508 -0.9398)
			(stroke
				(width 0)
				(type default)
			)
			(fill no)
			(layer "F.Fab")
		)
		(pad "1" smd custom
			(at 0 -0.4445 90)
			(size 0.1397 0.1397)
			(layers "F.Cu" "F.Mask" "F.Paste")
			(net "FLA0_SPI_RST")
			(options
				(clearance outline)
				(anchor circle)
			)
			(primitives
				(gr_poly
					(pts
						(arc
							(start -0.1778 -0.2794)
							(mid -0.249642 -0.249642)
							(end -0.2794 -0.1778)
						)
						(arc
							(start -0.2794 0.1778)
							(mid -0.249642 0.249642)
							(end -0.1778 0.2794)
						)
						(arc
							(start 0.1778 0.2794)
							(mid 0.249642 0.249642)
							(end 0.2794 0.1778)
						)
						(arc
							(start 0.2794 -0.1778)
							(mid 0.249642 -0.249642)
							(end 0.1778 -0.2794)
						)
					)
					(width 0)
					(fill yes)
				)
			)
		)
		(pad "2" smd custom
			(at 0 0.4445 90)
			(size 0.1397 0.1397)
			(layers "F.Cu" "F.Mask" "F.Paste")
			(net "RST_BMC_EXTRST_N")
			(options
				(clearance outline)
				(anchor circle)
			)
			(primitives
				(gr_poly
					(pts
						(arc
							(start -0.1778 -0.2794)
							(mid -0.249642 -0.249642)
							(end -0.2794 -0.1778)
						)
						(arc
							(start -0.2794 0.1778)
							(mid -0.249642 0.249642)
							(end -0.1778 0.2794)
						)
						(arc
							(start 0.1778 0.2794)
							(mid 0.249642 0.249642)
							(end 0.2794 0.1778)
						)
						(arc
							(start 0.2794 -0.1778)
							(mid 0.249642 -0.249642)
							(end 0.1778 -0.2794)
						)
					)
					(width 0)
					(fill yes)
				)
			)
		)
	)
	(footprint ""
		(layer "F.Cu")
		(at 153.203656 -137.795762 180)
		(property "Reference" "R522"
			(at 0 0 180)
			(layer "F.SilkS")
			(hide yes)
			(effects
				(font
					(size 1.27 1.27)
				)
			)
		)
		(property "Value" "0R2J-2-GP"
			(at 0.064008 -3.993896 180)
			(unlocked yes)
			(layer "F.Fab")
			(hide yes)
			(effects
				(font
					(size 1.016 1.016)
					(thickness 0.1524)
				)
			)
		)
		(property "Device Type" "R402H16"
			(at 0.064008 -5.517896 180)
			(unlocked yes)
			(layer "F.Fab")
			(hide yes)
			(effects
				(font
					(size 1.016 1.016)
					(thickness 0.1524)
				)
			)
		)
		(duplicate_pad_numbers_are_jumpers no)
		(fp_line
			(start 0.508 -0.9398)
			(end -0.508 -0.9398)
			(stroke
				(width 0.1524)
				(type default)
			)
			(layer "F.SilkS")
		)
		(fp_line
			(start -0.508 -0.9398)
			(end -0.508 0.9398)
			(stroke
				(width 0.1524)
				(type default)
			)
			(layer "F.SilkS")
		)
		(fp_rect
			(start -0.508 0.9398)
			(end 0.508 -0.9398)
			(stroke
				(width 0)
				(type default)
			)
			(fill no)
			(layer "F.CrtYd")
		)
		(fp_rect
			(start -0.508 0.9398)
			(end 0.508 -0.9398)
			(stroke
				(width 0)
				(type default)
			)
			(fill no)
			(layer "F.Fab")
		)
		(pad "1" smd custom
			(at 0 -0.4445 180)
			(size 0.1397 0.1397)
			(layers "F.Cu" "F.Mask" "F.Paste")
			(net "P1V8_STBY_EN_R")
			(options
				(clearance outline)
				(anchor circle)
			)
			(primitives
				(gr_poly
					(pts
						(arc
							(start -0.1778 -0.2794)
							(mid -0.249642 -0.249642)
							(end -0.2794 -0.1778)
						)
						(arc
							(start -0.2794 0.1778)
							(mid -0.249642 0.249642)
							(end -0.1778 0.2794)
						)
						(arc
							(start 0.1778 0.2794)
							(mid 0.249642 0.249642)
							(end 0.2794 0.1778)
						)
						(arc
							(start 0.2794 -0.1778)
							(mid 0.249642 -0.249642)
							(end 0.1778 -0.2794)
						)
					)
					(width 0)
					(fill yes)
				)
			)
		)
		(pad "2" smd custom
			(at 0 0.4445 180)
			(size 0.1397 0.1397)
			(layers "F.Cu" "F.Mask" "F.Paste")
			(net "PWRGD_P2V5_STBY")
			(options
				(clearance outline)
				(anchor circle)
			)
			(primitives
				(gr_poly
					(pts
						(arc
							(start -0.1778 -0.2794)
							(mid -0.249642 -0.249642)
							(end -0.2794 -0.1778)
						)
						(arc
							(start -0.2794 0.1778)
							(mid -0.249642 0.249642)
							(end -0.1778 0.2794)
						)
						(arc
							(start 0.1778 0.2794)
							(mid 0.249642 0.249642)
							(end 0.2794 0.1778)
						)
						(arc
							(start 0.2794 -0.1778)
							(mid 0.249642 -0.249642)
							(end 0.1778 -0.2794)
						)
					)
					(width 0)
					(fill yes)
				)
			)
		)
	)
)
